# SCM (Grand Teton) — schematic netlist excerpt (pin names and nets, part order shuffled) for the footprints in the layout excerpt that follows; sources: Cadence DE-HDL packaged netlist, KiCad conversion of 12092022_DA0F0TMDCD0_F0T_Management_Board_D_brd_V3_OCP.brd

C41  Q_CAP  0.1UF 25V 10% X7R  pkg 0402  page 15 : A = P1V8_BMC_USB2AV18 ; B = GND
C307  Q_CAP  0.1UF 25V 10% X7R  pkg 0402  page 15 : A = P1V8_SENSOR ; B = GND

(kicad_pcb
	(version 20260206)
	(generator "pcbnew")
	(generator_version "10.0")
	(general
		(thickness 1.6)
		(legacy_teardrops no)
	)
	(paper "A4")
	(title_block
		(title "12092022_DA0F0TMDCD0_F0T_Management_Board_D_brd_V3_OCP.brd")
		(comment 1 "Grand Teton / footprints 1047-1048 of 1440")
	)
	(layers
		(0 "F.Cu" signal "TOP")
		(4 "In1.Cu" signal "GND")
		(6 "In2.Cu" signal "IN1")
		(8 "In3.Cu" signal "GND1")
		(10 "In4.Cu" signal "IN2")
		(12 "In5.Cu" signal "VCC")
		(14 "In6.Cu" signal "VCC1")
		(16 "In7.Cu" signal "IN3")
		(18 "In8.Cu" signal "GND2")
		(20 "In9.Cu" signal "IN4")
		(22 "In10.Cu" signal "GND3")
		(2 "B.Cu" signal "BOTTOM")
		(9 "F.Adhes" user "F.Adhesive")
		(11 "B.Adhes" user "B.Adhesive")
		(13 "F.Paste" user "Package Geometry/Pastemask Top")
		(15 "B.Paste" user "Package Geometry/Pastemask Bottom")
		(5 "F.SilkS" user "Ref Des/Silkscreen Top")
		(7 "B.SilkS" user "Ref Des/Silkscreen Bottom")
		(1 "F.Mask" user "Board Geometry/Soldermask Top")
		(3 "B.Mask" user "Board Geometry/Soldermask Bottom")
		(17 "Dwgs.User" user "User.Drawings")
		(19 "Cmts.User" user "User.Comments")
		(21 "Eco1.User" user "User.Eco1")
		(23 "Eco2.User" user "User.Eco2")
		(25 "Edge.Cuts" user "Board Geometry/Outline")
		(27 "Margin" user)
		(31 "F.CrtYd" user "Package Geometry/Place Bound Top")
		(29 "B.CrtYd" user "Package Geometry/Place Bound Bottom")
		(35 "F.Fab" user "Ref Des/Assembly Top")
		(33 "B.Fab" user "Ref Des/Assembly Bottom")
	)
	(footprint ""
		(layer "B.Cu")
		(at 58.381646 -46.974252 180)
		(property "Reference" "C41"
			(at 0 0 0)
			(layer "B.SilkS")
			(hide yes)
			(effects
				(font
					(size 1.27 1.27)
				)
				(justify mirror)
			)
		)
		(property "Value" ""
			(at 0 0 0)
			(layer "B.Fab")
			(effects
				(font
					(size 1.27 1.27)
				)
				(justify mirror)
			)
		)
		(duplicate_pad_numbers_are_jumpers no)
		(fp_line
			(start 0.7874 0.4064)
			(end 0.7874 -0.4064)
			(stroke
				(width 0.1524)
				(type default)
			)
			(layer "B.SilkS")
		)
		(fp_line
			(start 0.7874 -0.4064)
			(end -0.7874 -0.4064)
			(stroke
				(width 0.1524)
				(type default)
			)
			(layer "B.SilkS")
		)
		(fp_line
			(start -0.7874 0.4064)
			(end 0.7874 0.4064)
			(stroke
				(width 0.1524)
				(type default)
			)
			(layer "B.SilkS")
		)
		(fp_line
			(start -0.7874 -0.4064)
			(end -0.7874 0.4064)
			(stroke
				(width 0.1524)
				(type default)
			)
			(layer "B.SilkS")
		)
		(fp_line
			(start 0.67945 0.3048)
			(end 0.67945 -0.305054)
			(stroke
				(width 0.1)
				(type default)
			)
			(layer "B.Fab")
		)
		(fp_line
			(start 0.67945 -0.305054)
			(end 0.12065 -0.305054)
			(stroke
				(width 0.1)
				(type default)
			)
			(layer "B.Fab")
		)
		(fp_line
			(start 0.12065 0.3048)
			(end 0.67945 0.3048)
			(stroke
				(width 0.1)
				(type default)
			)
			(layer "B.Fab")
		)
		(fp_line
			(start 0.12065 0.2794)
			(end 0.12065 0.3048)
			(stroke
				(width 0.1)
				(type default)
			)
			(layer "B.Fab")
		)
		(fp_line
			(start 0.12065 -0.2794)
			(end -0.12065 -0.2794)
			(stroke
				(width 0.1)
				(type default)
			)
			(layer "B.Fab")
		)
		(fp_line
			(start 0.12065 -0.305054)
			(end 0.12065 -0.2794)
			(stroke
				(width 0.1)
				(type default)
			)
			(layer "B.Fab")
		)
		(fp_line
			(start -0.120396 0.3048)
			(end -0.120396 0.2794)
			(stroke
				(width 0.1)
				(type default)
			)
			(layer "B.Fab")
		)
		(fp_line
			(start -0.120396 0.2794)
			(end 0.12065 0.2794)
			(stroke
				(width 0.1)
				(type default)
			)
			(layer "B.Fab")
		)
		(fp_line
			(start -0.12065 -0.2794)
			(end -0.12065 -0.3048)
			(stroke
				(width 0.1)
				(type default)
			)
			(layer "B.Fab")
		)
		(fp_line
			(start -0.12065 -0.3048)
			(end -0.67945 -0.3048)
			(stroke
				(width 0.1)
				(type default)
			)
			(layer "B.Fab")
		)
		(fp_line
			(start -0.67945 0.3048)
			(end -0.120396 0.3048)
			(stroke
				(width 0.1)
				(type default)
			)
			(layer "B.Fab")
		)
		(fp_line
			(start -0.67945 -0.3048)
			(end -0.67945 0.3048)
			(stroke
				(width 0.1)
				(type default)
			)
			(layer "B.Fab")
		)
		(pad "1" smd circle
			(at 0.40005 0)
			(size 0 0)
			(layers "B.Cu" "B.Mask" "B.Paste")
			(net "P1V8_BMC_USB2AV18")
		)
		(pad "2" smd circle
			(at -0.40005 0)
			(size 0 0)
			(layers "B.Cu" "B.Mask" "B.Paste")
			(net "GND")
		)
	)
	(footprint ""
		(layer "B.Cu")
		(at 50.858674 -71.824342 180)
		(property "Reference" "C307"
			(at 0 0 0)
			(layer "B.SilkS")
			(hide yes)
			(effects
				(font
					(size 1.27 1.27)
				)
				(justify mirror)
			)
		)
		(property "Value" ""
			(at 0 0 0)
			(layer "B.Fab")
			(effects
				(font
					(size 1.27 1.27)
				)
				(justify mirror)
			)
		)
		(duplicate_pad_numbers_are_jumpers no)
		(fp_line
			(start 0.7874 0.4064)
			(end 0.7874 -0.4064)
			(stroke
				(width 0.1524)
				(type default)
			)
			(layer "B.SilkS")
		)
		(fp_line
			(start 0.7874 -0.4064)
			(end -0.7874 -0.4064)
			(stroke
				(width 0.1524)
				(type default)
			)
			(layer "B.SilkS")
		)
		(fp_line
			(start -0.7874 0.4064)
			(end 0.7874 0.4064)
			(stroke
				(width 0.1524)
				(type default)
			)
			(layer "B.SilkS")
		)
		(fp_line
			(start -0.7874 -0.4064)
			(end -0.7874 0.4064)
			(stroke
				(width 0.1524)
				(type default)
			)
			(layer "B.SilkS")
		)
		(fp_line
			(start 0.67945 0.3048)
			(end 0.67945 -0.305054)
			(stroke
				(width 0.1)
				(type default)
			)
			(layer "B.Fab")
		)
		(fp_line
			(start 0.67945 -0.305054)
			(end 0.12065 -0.305054)
			(stroke
				(width 0.1)
				(type default)
			)
			(layer "B.Fab")
		)
		(fp_line
			(start 0.12065 0.3048)
			(end 0.67945 0.3048)
			(stroke
				(width 0.1)
				(type default)
			)
			(layer "B.Fab")
		)
		(fp_line
			(start 0.12065 0.2794)
			(end 0.12065 0.3048)
			(stroke
				(width 0.1)
				(type default)
			)
			(layer "B.Fab")
		)
		(fp_line
			(start 0.12065 -0.2794)
			(end -0.12065 -0.2794)
			(stroke
				(width 0.1)
				(type default)
			)
			(layer "B.Fab")
		)
		(fp_line
			(start 0.12065 -0.305054)
			(end 0.12065 -0.2794)
			(stroke
				(width 0.1)
				(type default)
			)
			(layer "B.Fab")
		)
		(fp_line
			(start -0.120396 0.3048)
			(end -0.120396 0.2794)
			(stroke
				(width 0.1)
				(type default)
			)
			(layer "B.Fab")
		)
		(fp_line
			(start -0.120396 0.2794)
			(end 0.12065 0.2794)
			(stroke
				(width 0.1)
				(type default)
			)
			(layer "B.Fab")
		)
		(fp_line
			(start -0.12065 -0.2794)
			(end -0.12065 -0.3048)
			(stroke
				(width 0.1)
				(type default)
			)
			(layer "B.Fab")
		)
		(fp_line
			(start -0.12065 -0.3048)
			(end -0.67945 -0.3048)
			(stroke
				(width 0.1)
				(type default)
			)
			(layer "B.Fab")
		)
		(fp_line
			(start -0.67945 0.3048)
			(end -0.120396 0.3048)
			(stroke
				(width 0.1)
				(type default)
			)
			(layer "B.Fab")
		)
		(fp_line
			(start -0.67945 -0.3048)
			(end -0.67945 0.3048)
			(stroke
				(width 0.1)
				(type default)
			)
			(layer "B.Fab")
		)
		(pad "1" smd circle
			(at 0.40005 0)
			(size 0 0)
			(layers "B.Cu" "B.Mask" "B.Paste")
			(net "P1V8_SENSOR")
		)
		(pad "2" smd circle
			(at -0.40005 0)
			(size 0 0)
			(layers "B.Cu" "B.Mask" "B.Paste")
			(net "GND")
		)
	)
)
